(kicad_pcb
	(version 20260206)
	(generator "pcbnew")
	(generator_version "10.0")
	(general
		(thickness 1.6)
		(legacy_teardrops no)
	)
	(paper "A4")
	(title_block
		(title "Bryce Canyon_IOM_IOC_16318-2_OCP.brd")
		(comment 1 "Bryce Canyon / footprint 592 of 1605 (U1), pads 711-831 of 896")
	)
	(layers
		(0 "F.Cu" signal "TOP")
		(4 "In1.Cu" signal "L2GND")
		(6 "In2.Cu" signal "L3")
		(8 "In3.Cu" signal "L4VCC")
		(10 "In4.Cu" signal "L5VCC")
		(12 "In5.Cu" signal "L6")
		(14 "In6.Cu" signal "L7GND")
		(2 "B.Cu" signal "BOTTOM")
		(9 "F.Adhes" user "F.Adhesive")
		(11 "B.Adhes" user "B.Adhesive")
		(13 "F.Paste" user "Package Geometry/Pastemask Top")
		(15 "B.Paste" user "Package Geometry/Pastemask Bottom")
		(5 "F.SilkS" user "Ref Des/Silkscreen Top")
		(7 "B.SilkS" user "Ref Des/Silkscreen Bottom")
		(1 "F.Mask" user "Board Geometry/Soldermask Top")
		(3 "B.Mask" user "Board Geometry/Soldermask Bottom")
		(17 "Dwgs.User" user "User.Drawings")
		(19 "Cmts.User" user "User.Comments")
		(21 "Eco1.User" user "User.Eco1")
		(23 "Eco2.User" user "User.Eco2")
		(25 "Edge.Cuts" user "Board Geometry/Outline")
		(27 "Margin" user)
		(31 "F.CrtYd" user "Package Geometry/Place Bound Top")
		(29 "B.CrtYd" user "Package Geometry/Place Bound Bottom")
		(35 "F.Fab" user "Ref Des/Assembly Top")
		(33 "B.Fab" user "Ref Des/Assembly Bottom")
	)
	(footprint ""
		(layer "F.Cu")
		(at 192.79997 -65.099946 180)
		(property "Reference" "U1"
			(at 0 0 180)
			(layer "F.SilkS")
			(hide yes)
			(effects
				(font
					(size 1.27 1.27)
				)
			)
		)
		(property "Value" "SAS3008C0-1-DB-500020657-1-GP"
			(at -20.374102 -5.0292 180)
			(unlocked yes)
			(layer "F.Fab")
			(hide yes)
			(effects
				(font
					(size 1.016 1.016)
					(thickness 0.1524)
				)
			)
		)
		(property "Device Type" "BGA896D25H78"
			(at -20.374102 -6.5532 180)
			(unlocked yes)
			(layer "F.Fab")
			(hide yes)
			(effects
				(font
					(size 1.016 1.016)
					(thickness 0.1524)
				)
			)
		)
		(duplicate_pad_numbers_are_jumpers no)
		(pad "P25" smd circle
			(at 7.599934 -1.199896 180)
			(size 0.3556 0.3556)
			(layers "F.Cu" "F.Mask" "F.Paste")
			(net "GND")
		)
		(pad "P26" smd circle
			(at 8.400034 -1.199896 180)
			(size 0.3556 0.3556)
			(layers "F.Cu" "F.Mask" "F.Paste")
			(net "P1V8")
		)
		(pad "P27" smd circle
			(at 9.19988 -1.199896 180)
			(size 0.3556 0.3556)
			(layers "F.Cu" "F.Mask" "F.Paste")
			(net "GND")
		)
		(pad "P28" smd circle
			(at 9.99998 -1.199896 180)
			(size 0.3556 0.3556)
			(layers "F.Cu" "F.Mask" "F.Paste")
			(net "IOC_SCL_3")
		)
		(pad "P29" smd circle
			(at 10.80008 -1.199896 180)
			(size 0.3556 0.3556)
			(layers "F.Cu" "F.Mask" "F.Paste")
			(net "IOC_CLK_SEL0")
		)
		(pad "P30" smd circle
			(at 11.599926 -1.199896 180)
			(size 0.3556 0.3556)
			(layers "F.Cu" "F.Mask" "F.Paste")
			(net "IOC_SCL_1")
		)
		(pad "R1" smd circle
			(at -11.599926 -0.40005 180)
			(size 0.3556 0.3556)
			(layers "F.Cu" "F.Mask" "F.Paste")
			(net "GND")
		)
		(pad "R2" smd circle
			(at -10.80008 -0.40005 180)
			(size 0.3556 0.3556)
			(layers "F.Cu" "F.Mask" "F.Paste")
			(net "GND")
		)
		(pad "R3" smd circle
			(at -9.99998 -0.40005 180)
			(size 0.3556 0.3556)
			(layers "F.Cu" "F.Mask" "F.Paste")
			(net "GND")
		)
		(pad "R4" smd circle
			(at -9.19988 -0.40005 180)
			(size 0.3556 0.3556)
			(layers "F.Cu" "F.Mask" "F.Paste")
			(net "GND")
		)
		(pad "R5" smd circle
			(at -8.400034 -0.40005 180)
			(size 0.3556 0.3556)
			(layers "F.Cu" "F.Mask" "F.Paste")
			(net "IOC_SIO_BLINK")
		)
		(pad "R6" smd circle
			(at -7.599934 -0.40005 180)
			(size 0.3556 0.3556)
			(layers "F.Cu" "F.Mask" "F.Paste")
			(net "POWERLOSS#")
		)
		(pad "R7" smd circle
			(at -6.800088 -0.40005 180)
			(size 0.3556 0.3556)
			(layers "F.Cu" "F.Mask" "F.Paste")
			(net "GND")
		)
		(pad "R8" smd circle
			(at -5.999988 -0.40005 180)
			(size 0.3556 0.3556)
			(layers "F.Cu" "F.Mask" "F.Paste")
			(net "GND")
		)
		(pad "R9" smd circle
			(at -5.199888 -0.40005 180)
			(size 0.3556 0.3556)
			(layers "F.Cu" "F.Mask" "F.Paste")
			(net "GND")
		)
		(pad "R10" smd circle
			(at -4.400042 -0.40005 180)
			(size 0.3556 0.3556)
			(layers "F.Cu" "F.Mask" "F.Paste")
			(net "GND")
		)
		(pad "R11" smd circle
			(at -3.599942 -0.40005 180)
			(size 0.3556 0.3556)
			(layers "F.Cu" "F.Mask" "F.Paste")
			(net "GND")
		)
		(pad "R12" smd circle
			(at -2.800096 -0.40005 180)
			(size 0.3556 0.3556)
			(layers "F.Cu" "F.Mask" "F.Paste")
			(net "P0V975")
		)
		(pad "R13" smd circle
			(at -1.999996 -0.40005 180)
			(size 0.3556 0.3556)
			(layers "F.Cu" "F.Mask" "F.Paste")
			(net "GND")
		)
		(pad "R14" smd circle
			(at -1.199896 -0.40005 180)
			(size 0.3556 0.3556)
			(layers "F.Cu" "F.Mask" "F.Paste")
			(net "P0V975")
		)
		(pad "R15" smd circle
			(at -0.40005 -0.40005 180)
			(size 0.3556 0.3556)
			(layers "F.Cu" "F.Mask" "F.Paste")
			(net "GND")
		)
		(pad "R16" smd circle
			(at 0.40005 -0.40005 180)
			(size 0.3556 0.3556)
			(layers "F.Cu" "F.Mask" "F.Paste")
			(net "P0V975")
		)
		(pad "R17" smd circle
			(at 1.199896 -0.40005 180)
			(size 0.3556 0.3556)
			(layers "F.Cu" "F.Mask" "F.Paste")
			(net "GND")
		)
		(pad "R18" smd circle
			(at 1.999996 -0.40005 180)
			(size 0.3556 0.3556)
			(layers "F.Cu" "F.Mask" "F.Paste")
			(net "P0V975")
		)
		(pad "R19" smd circle
			(at 2.800096 -0.40005 180)
			(size 0.3556 0.3556)
			(layers "F.Cu" "F.Mask" "F.Paste")
			(net "GND")
		)
		(pad "R20" smd circle
			(at 3.599942 -0.40005 180)
			(size 0.3556 0.3556)
			(layers "F.Cu" "F.Mask" "F.Paste")
			(net "P0V975")
		)
		(pad "R21" smd circle
			(at 4.400042 -0.40005 180)
			(size 0.3556 0.3556)
			(layers "F.Cu" "F.Mask" "F.Paste")
			(net "GND")
		)
		(pad "R22" smd circle
			(at 5.199888 -0.40005 180)
			(size 0.3556 0.3556)
			(layers "F.Cu" "F.Mask" "F.Paste")
			(net "GND")
		)
		(pad "R23" smd circle
			(at 5.999988 -0.40005 180)
			(size 0.3556 0.3556)
			(layers "F.Cu" "F.Mask" "F.Paste")
			(net "GND")
		)
		(pad "R24" smd circle
			(at 6.800088 -0.40005 180)
			(size 0.3556 0.3556)
			(layers "F.Cu" "F.Mask" "F.Paste")
			(net "GND")
		)
		(pad "R25" smd circle
			(at 7.599934 -0.40005 180)
			(size 0.3556 0.3556)
			(layers "F.Cu" "F.Mask" "F.Paste")
			(net "GND")
		)
		(pad "R26" smd circle
			(at 8.400034 -0.40005 180)
			(size 0.3556 0.3556)
			(layers "F.Cu" "F.Mask" "F.Paste")
			(net "GND")
		)
		(pad "R27" smd circle
			(at 9.19988 -0.40005 180)
			(size 0.3556 0.3556)
			(layers "F.Cu" "F.Mask" "F.Paste")
			(net "P1V8")
		)
		(pad "R28" smd circle
			(at 9.99998 -0.40005 180)
			(size 0.3556 0.3556)
			(layers "F.Cu" "F.Mask" "F.Paste")
			(net "IOC_SDA_4")
		)
		(pad "R29" smd circle
			(at 10.80008 -0.40005 180)
			(size 0.3556 0.3556)
			(layers "F.Cu" "F.Mask" "F.Paste")
			(net "IOC_SDA_0")
		)
		(pad "R30" smd circle
			(at 11.599926 -0.40005 180)
			(size 0.3556 0.3556)
			(layers "F.Cu" "F.Mask" "F.Paste")
			(net "SYS_CORE_TRI#")
		)
		(pad "T1" smd circle
			(at -11.599926 0.40005 180)
			(size 0.3556 0.3556)
			(layers "F.Cu" "F.Mask" "F.Paste")
			(net "RTRIM")
		)
		(pad "T2" smd circle
			(at -10.80008 0.40005 180)
			(size 0.3556 0.3556)
			(layers "F.Cu" "F.Mask" "F.Paste")
			(net "RTRIM#")
		)
		(pad "T3" smd circle
			(at -9.99998 0.40005 180)
			(size 0.3556 0.3556)
			(layers "F.Cu" "F.Mask" "F.Paste")
			(net "GND")
		)
		(pad "T4" smd circle
			(at -9.19988 0.40005 180)
			(size 0.3556 0.3556)
			(layers "F.Cu" "F.Mask" "F.Paste")
			(net "OSC_REF_CLK")
		)
		(pad "T5" smd circle
			(at -8.400034 0.40005 180)
			(size 0.3556 0.3556)
			(layers "F.Cu" "F.Mask" "F.Paste")
			(net "GND")
		)
		(pad "T6" smd circle
			(at -7.599934 0.40005 180)
			(size 0.3556 0.3556)
			(layers "F.Cu" "F.Mask" "F.Paste")
			(net "SIO_DIN_0")
		)
		(pad "T7" smd circle
			(at -6.800088 0.40005 180)
			(size 0.3556 0.3556)
			(layers "F.Cu" "F.Mask" "F.Paste")
			(net "GND")
		)
		(pad "T8" smd circle
			(at -5.999988 0.40005 180)
			(size 0.3556 0.3556)
			(layers "F.Cu" "F.Mask" "F.Paste")
			(net "GND")
		)
		(pad "T9" smd circle
			(at -5.199888 0.40005 180)
			(size 0.3556 0.3556)
			(layers "F.Cu" "F.Mask" "F.Paste")
			(net "SYS_PLL_VDD")
		)
		(pad "T10" smd circle
			(at -4.400042 0.40005 180)
			(size 0.3556 0.3556)
			(layers "F.Cu" "F.Mask" "F.Paste")
			(net "GND")
		)
		(pad "T11" smd circle
			(at -3.599942 0.40005 180)
			(size 0.3556 0.3556)
			(layers "F.Cu" "F.Mask" "F.Paste")
			(net "GND")
		)
		(pad "T12" smd circle
			(at -2.800096 0.40005 180)
			(size 0.3556 0.3556)
			(layers "F.Cu" "F.Mask" "F.Paste")
			(net "GND")
		)
		(pad "T13" smd circle
			(at -1.999996 0.40005 180)
			(size 0.3556 0.3556)
			(layers "F.Cu" "F.Mask" "F.Paste")
			(net "P0V975")
		)
		(pad "T14" smd circle
			(at -1.199896 0.40005 180)
			(size 0.3556 0.3556)
			(layers "F.Cu" "F.Mask" "F.Paste")
			(net "GND")
		)
		(pad "T15" smd circle
			(at -0.40005 0.40005 180)
			(size 0.3556 0.3556)
			(layers "F.Cu" "F.Mask" "F.Paste")
			(net "P0V975")
		)
		(pad "T16" smd circle
			(at 0.40005 0.40005 180)
			(size 0.3556 0.3556)
			(layers "F.Cu" "F.Mask" "F.Paste")
			(net "GND")
		)
		(pad "T17" smd circle
			(at 1.199896 0.40005 180)
			(size 0.3556 0.3556)
			(layers "F.Cu" "F.Mask" "F.Paste")
			(net "P0V975")
		)
		(pad "T18" smd circle
			(at 1.999996 0.40005 180)
			(size 0.3556 0.3556)
			(layers "F.Cu" "F.Mask" "F.Paste")
			(net "GND")
		)
		(pad "T19" smd circle
			(at 2.800096 0.40005 180)
			(size 0.3556 0.3556)
			(layers "F.Cu" "F.Mask" "F.Paste")
			(net "P0V975")
		)
		(pad "T20" smd circle
			(at 3.599942 0.40005 180)
			(size 0.3556 0.3556)
			(layers "F.Cu" "F.Mask" "F.Paste")
			(net "GND")
		)
		(pad "T21" smd circle
			(at 4.400042 0.40005 180)
			(size 0.3556 0.3556)
			(layers "F.Cu" "F.Mask" "F.Paste")
			(net "P0V975")
		)
		(pad "T22" smd circle
			(at 5.199888 0.40005 180)
			(size 0.3556 0.3556)
			(layers "F.Cu" "F.Mask" "F.Paste")
			(net "GND")
		)
		(pad "T23" smd circle
			(at 5.999988 0.40005 180)
			(size 0.3556 0.3556)
			(layers "F.Cu" "F.Mask" "F.Paste")
			(net "GND")
		)
		(pad "T24" smd circle
			(at 6.800088 0.40005 180)
			(size 0.3556 0.3556)
			(layers "F.Cu" "F.Mask" "F.Paste")
			(net "GND")
		)
		(pad "T25" smd circle
			(at 7.599934 0.40005 180)
			(size 0.3556 0.3556)
			(layers "F.Cu" "F.Mask" "F.Paste")
			(net "GND")
		)
		(pad "T26" smd circle
			(at 8.400034 0.40005 180)
			(size 0.3556 0.3556)
			(layers "F.Cu" "F.Mask" "F.Paste")
			(net "P1V8")
		)
		(pad "T27" smd circle
			(at 9.19988 0.40005 180)
			(size 0.3556 0.3556)
			(layers "F.Cu" "F.Mask" "F.Paste")
			(net "GND")
		)
		(pad "T28" smd circle
			(at 9.99998 0.40005 180)
			(size 0.3556 0.3556)
			(layers "F.Cu" "F.Mask" "F.Paste")
			(net "IOC_CLK_SEL1")
		)
		(pad "T29" smd circle
			(at 10.80008 0.40005 180)
			(size 0.3556 0.3556)
			(layers "F.Cu" "F.Mask" "F.Paste")
			(net "SYS_HB_LED")
		)
		(pad "T30" smd circle
			(at 11.599926 0.40005 180)
			(size 0.3556 0.3556)
			(layers "F.Cu" "F.Mask" "F.Paste")
			(net "SBL_SCL")
		)
		(pad "U1" smd circle
			(at -11.599926 1.199896 180)
			(size 0.3556 0.3556)
			(layers "F.Cu" "F.Mask" "F.Paste")
			(net "SAS0_VDDH")
		)
		(pad "U2" smd circle
			(at -10.80008 1.199896 180)
			(size 0.3556 0.3556)
			(layers "F.Cu" "F.Mask" "F.Paste")
			(net "GND")
		)
		(pad "U3" smd circle
			(at -9.99998 1.199896 180)
			(size 0.3556 0.3556)
			(layers "F.Cu" "F.Mask" "F.Paste")
			(net "GND")
		)
		(pad "U4" smd circle
			(at -9.19988 1.199896 180)
			(size 0.3556 0.3556)
			(layers "F.Cu" "F.Mask" "F.Paste")
			(net "GND")
		)
		(pad "U5" smd circle
			(at -8.400034 1.199896 180)
			(size 0.3556 0.3556)
			(layers "F.Cu" "F.Mask" "F.Paste")
			(net "GND")
		)
		(pad "U6" smd circle
			(at -7.599934 1.199896 180)
			(size 0.3556 0.3556)
			(layers "F.Cu" "F.Mask" "F.Paste")
			(net "GND")
		)
		(pad "U7" smd circle
			(at -6.800088 1.199896 180)
			(size 0.3556 0.3556)
			(layers "F.Cu" "F.Mask" "F.Paste")
			(net "GND")
		)
		(pad "U8" smd circle
			(at -5.999988 1.199896 180)
			(size 0.3556 0.3556)
			(layers "F.Cu" "F.Mask" "F.Paste")
			(net "GND")
		)
		(pad "U9" smd circle
			(at -5.199888 1.199896 180)
			(size 0.3556 0.3556)
			(layers "F.Cu" "F.Mask" "F.Paste")
			(net "GND")
		)
		(pad "U10" smd circle
			(at -4.400042 1.199896 180)
			(size 0.3556 0.3556)
			(layers "F.Cu" "F.Mask" "F.Paste")
			(net "SHELL_PLL_VDD")
		)
		(pad "U11" smd circle
			(at -3.599942 1.199896 180)
			(size 0.3556 0.3556)
			(layers "F.Cu" "F.Mask" "F.Paste")
			(net "GND")
		)
		(pad "U12" smd circle
			(at -2.800096 1.199896 180)
			(size 0.3556 0.3556)
			(layers "F.Cu" "F.Mask" "F.Paste")
			(net "P0V975")
		)
		(pad "U13" smd circle
			(at -1.999996 1.199896 180)
			(size 0.3556 0.3556)
			(layers "F.Cu" "F.Mask" "F.Paste")
			(net "GND")
		)
		(pad "U14" smd circle
			(at -1.199896 1.199896 180)
			(size 0.3556 0.3556)
			(layers "F.Cu" "F.Mask" "F.Paste")
			(net "P0V975")
		)
		(pad "U15" smd circle
			(at -0.40005 1.199896 180)
			(size 0.3556 0.3556)
			(layers "F.Cu" "F.Mask" "F.Paste")
			(net "GND")
		)
		(pad "U16" smd circle
			(at 0.40005 1.199896 180)
			(size 0.3556 0.3556)
			(layers "F.Cu" "F.Mask" "F.Paste")
			(net "P0V975")
		)
		(pad "U17" smd circle
			(at 1.199896 1.199896 180)
			(size 0.3556 0.3556)
			(layers "F.Cu" "F.Mask" "F.Paste")
			(net "GND")
		)
		(pad "U18" smd circle
			(at 1.999996 1.199896 180)
			(size 0.3556 0.3556)
			(layers "F.Cu" "F.Mask" "F.Paste")
			(net "P0V975")
		)
		(pad "U19" smd circle
			(at 2.800096 1.199896 180)
			(size 0.3556 0.3556)
			(layers "F.Cu" "F.Mask" "F.Paste")
			(net "GND")
		)
		(pad "U20" smd circle
			(at 3.599942 1.199896 180)
			(size 0.3556 0.3556)
			(layers "F.Cu" "F.Mask" "F.Paste")
			(net "P0V975")
		)
		(pad "U21" smd circle
			(at 4.400042 1.199896 180)
			(size 0.3556 0.3556)
			(layers "F.Cu" "F.Mask" "F.Paste")
			(net "GND")
		)
		(pad "U22" smd circle
			(at 5.199888 1.199896 180)
			(size 0.3556 0.3556)
			(layers "F.Cu" "F.Mask" "F.Paste")
			(net "GND")
		)
		(pad "U23" smd circle
			(at 5.999988 1.199896 180)
			(size 0.3556 0.3556)
			(layers "F.Cu" "F.Mask" "F.Paste")
			(net "GND")
		)
		(pad "U24" smd circle
			(at 6.800088 1.199896 180)
			(size 0.3556 0.3556)
			(layers "F.Cu" "F.Mask" "F.Paste")
			(net "GND")
		)
		(pad "U25" smd circle
			(at 7.599934 1.199896 180)
			(size 0.3556 0.3556)
			(layers "F.Cu" "F.Mask" "F.Paste")
			(net "GND")
		)
		(pad "U26" smd circle
			(at 8.400034 1.199896 180)
			(size 0.3556 0.3556)
			(layers "F.Cu" "F.Mask" "F.Paste")
			(net "GND")
		)
		(pad "U27" smd circle
			(at 9.19988 1.199896 180)
			(size 0.3556 0.3556)
			(layers "F.Cu" "F.Mask" "F.Paste")
			(net "P1V8")
		)
		(pad "U28" smd circle
			(at 9.99998 1.199896 180)
			(size 0.3556 0.3556)
			(layers "F.Cu" "F.Mask" "F.Paste")
			(net "IOC_RESET#")
		)
		(pad "U29" smd circle
			(at 10.80008 1.199896 180)
			(size 0.3556 0.3556)
			(layers "F.Cu" "F.Mask" "F.Paste")
			(net "IOC_SDA_3")
		)
		(pad "U30" smd circle
			(at 11.599926 1.199896 180)
			(size 0.3556 0.3556)
			(layers "F.Cu" "F.Mask" "F.Paste")
			(net "CP_DONE")
		)
		(pad "V1" smd circle
			(at -11.599926 1.999996 180)
			(size 0.3556 0.3556)
			(layers "F.Cu" "F.Mask" "F.Paste")
			(net "PHY_IOC_TO_CON_B_3_DP_C")
		)
		(pad "V2" smd circle
			(at -10.80008 1.999996 180)
			(size 0.3556 0.3556)
			(layers "F.Cu" "F.Mask" "F.Paste")
			(net "PHY_IOC_TO_CON_B_3_DN_C")
		)
		(pad "V3" smd circle
			(at -9.99998 1.999996 180)
			(size 0.3556 0.3556)
			(layers "F.Cu" "F.Mask" "F.Paste")
			(net "GND")
		)
		(pad "V4" smd circle
			(at -9.19988 1.999996 180)
			(size 0.3556 0.3556)
			(layers "F.Cu" "F.Mask" "F.Paste")
			(net "PHY_CON_B_TO_IOC_3_DP")
		)
		(pad "V5" smd circle
			(at -8.400034 1.999996 180)
			(size 0.3556 0.3556)
			(layers "F.Cu" "F.Mask" "F.Paste")
			(net "PHY_CON_B_TO_IOC_3_DN")
		)
		(pad "V6" smd circle
			(at -7.599934 1.999996 180)
			(size 0.3556 0.3556)
			(layers "F.Cu" "F.Mask" "F.Paste")
			(net "GND")
		)
		(pad "V7" smd circle
			(at -6.800088 1.999996 180)
			(size 0.3556 0.3556)
			(layers "F.Cu" "F.Mask" "F.Paste")
			(net "SAS0_AVDD")
		)
		(pad "V8" smd circle
			(at -5.999988 1.999996 180)
			(size 0.3556 0.3556)
			(layers "F.Cu" "F.Mask" "F.Paste")
			(net "GND")
		)
		(pad "V9" smd circle
			(at -5.199888 1.999996 180)
			(size 0.3556 0.3556)
			(layers "F.Cu" "F.Mask" "F.Paste")
			(net "SAS0_AVDD")
		)
		(pad "V10" smd circle
			(at -4.400042 1.999996 180)
			(size 0.3556 0.3556)
			(layers "F.Cu" "F.Mask" "F.Paste")
			(net "GND")
		)
		(pad "V11" smd circle
			(at -3.599942 1.999996 180)
			(size 0.3556 0.3556)
			(layers "F.Cu" "F.Mask" "F.Paste")
			(net "VDDA_SAS_REF_CLK")
		)
		(pad "V12" smd circle
			(at -2.800096 1.999996 180)
			(size 0.3556 0.3556)
			(layers "F.Cu" "F.Mask" "F.Paste")
			(net "GND")
		)
		(pad "V13" smd circle
			(at -1.999996 1.999996 180)
			(size 0.3556 0.3556)
			(layers "F.Cu" "F.Mask" "F.Paste")
			(net "P0V975")
		)
		(pad "V14" smd circle
			(at -1.199896 1.999996 180)
			(size 0.3556 0.3556)
			(layers "F.Cu" "F.Mask" "F.Paste")
			(net "GND")
		)
		(pad "V15" smd circle
			(at -0.40005 1.999996 180)
			(size 0.3556 0.3556)
			(layers "F.Cu" "F.Mask" "F.Paste")
			(net "P0V975")
		)
		(pad "V16" smd circle
			(at 0.40005 1.999996 180)
			(size 0.3556 0.3556)
			(layers "F.Cu" "F.Mask" "F.Paste")
			(net "GND")
		)
		(pad "V17" smd circle
			(at 1.199896 1.999996 180)
			(size 0.3556 0.3556)
			(layers "F.Cu" "F.Mask" "F.Paste")
			(net "P0V975")
		)
		(pad "V18" smd circle
			(at 1.999996 1.999996 180)
			(size 0.3556 0.3556)
			(layers "F.Cu" "F.Mask" "F.Paste")
			(net "GND")
		)
		(pad "V19" smd circle
			(at 2.800096 1.999996 180)
			(size 0.3556 0.3556)
			(layers "F.Cu" "F.Mask" "F.Paste")
			(net "P0V975")
		)
		(pad "V20" smd circle
			(at 3.599942 1.999996 180)
			(size 0.3556 0.3556)
			(layers "F.Cu" "F.Mask" "F.Paste")
			(net "GND")
		)
		(pad "V21" smd circle
			(at 4.400042 1.999996 180)
			(size 0.3556 0.3556)
			(layers "F.Cu" "F.Mask" "F.Paste")
			(net "P0V975")
		)
		(pad "V22" smd circle
			(at 5.199888 1.999996 180)
			(size 0.3556 0.3556)
			(layers "F.Cu" "F.Mask" "F.Paste")
			(net "GND")
		)
		(pad "V23" smd circle
			(at 5.999988 1.999996 180)
			(size 0.3556 0.3556)
			(layers "F.Cu" "F.Mask" "F.Paste")
			(net "GND")
		)
		(pad "V24" smd circle
			(at 6.800088 1.999996 180)
			(size 0.3556 0.3556)
			(layers "F.Cu" "F.Mask" "F.Paste")
			(net "GND")
		)
		(pad "V25" smd circle
			(at 7.599934 1.999996 180)
			(size 0.3556 0.3556)
			(layers "F.Cu" "F.Mask" "F.Paste")
			(net "GND")
		)
	)
)
